(kicad_pcb
	(version 20260206)
	(generator "pcbnew")
	(generator_version "10.0")
	(general
		(thickness 1.6)
		(legacy_teardrops no)
	)
	(paper "A4")
	(title_block
		(title "panther-plus-userver — 13130-1b_20150205.brd")
		(comment 1 "Honey Badger (Wiwynn) / footprint 624 of 1509 (DIMM4), pads 191-197 of 210")
	)
	(layers
		(0 "F.Cu" signal "TOP")
		(4 "In1.Cu" signal "L2")
		(6 "In2.Cu" signal "L3")
		(8 "In3.Cu" signal "L4")
		(10 "In4.Cu" signal "L5")
		(12 "In5.Cu" signal "L6")
		(14 "In6.Cu" signal "L7")
		(16 "In7.Cu" signal "L8")
		(18 "In8.Cu" signal "L9")
		(20 "In9.Cu" signal "L10")
		(22 "In10.Cu" signal "L11")
		(2 "B.Cu" signal "BOTTOM")
		(9 "F.Adhes" user "F.Adhesive")
		(11 "B.Adhes" user "B.Adhesive")
		(13 "F.Paste" user "Package Geometry/Pastemask Top")
		(15 "B.Paste" user "Package Geometry/Pastemask Bottom")
		(5 "F.SilkS" user "Ref Des/Silkscreen Top")
		(7 "B.SilkS" user "Ref Des/Silkscreen Bottom")
		(1 "F.Mask" user "Board Geometry/Soldermask Top")
		(3 "B.Mask" user "Board Geometry/Soldermask Bottom")
		(17 "Dwgs.User" user "User.Drawings")
		(19 "Cmts.User" user "User.Comments")
		(21 "Eco1.User" user "User.Eco1")
		(23 "Eco2.User" user "User.Eco2")
		(25 "Edge.Cuts" user "Board Geometry/Outline")
		(27 "Margin" user)
		(31 "F.CrtYd" user "Package Geometry/Place Bound Top")
		(29 "B.CrtYd" user "Package Geometry/Place Bound Bottom")
		(35 "F.Fab" user "Ref Des/Assembly Top")
		(33 "B.Fab" user "Ref Des/Assembly Bottom")
	)
	(footprint ""
		(layer "F.Cu")
		(at 159.999934 -5.790692)
		(property "Reference" "DIMM4"
			(at 0 0 0)
			(layer "F.SilkS")
			(hide yes)
			(effects
				(font
					(size 1.27 1.27)
				)
			)
		)
		(property "Value" "DDR3-204P-174-COLAY-1-GP"
			(at -40.682164 -17.468088 0)
			(unlocked yes)
			(layer "F.Fab")
			(hide yes)
			(effects
				(font
					(size 1.016 1.016)
					(thickness 0.1524)
				)
			)
		)
		(property "Device Type" "AS0A626-H8SN-7H-COLAY-1"
			(at -40.682164 -18.992088 0)
			(unlocked yes)
			(layer "F.Fab")
			(hide yes)
			(effects
				(font
					(size 1.016 1.016)
					(thickness 0.1524)
				)
			)
		)
		(duplicate_pad_numbers_are_jumpers no)
		(pad "189" smd custom
			(at 27.15006 4.106672)
			(size 0.1143 0.1143)
			(layers "F.Cu" "F.Mask" "F.Paste")
			(net "GND")
			(options
				(clearance outline)
				(anchor circle)
			)
			(primitives
				(gr_poly
					(pts
						(xy 0 0.9017) (xy -0.03175 0.89916) (xy -0.0635 0.889) (xy -0.09144 0.87376) (xy -0.11684 0.85344)
						(xy -0.13716 0.82804) (xy -0.1524 0.8001) (xy -0.16256 0.76835) (xy -0.1651 0.7366) (xy -0.1651 -0.13462)
						(xy -0.17272 -0.14224) (xy -0.19812 -0.1778) (xy -0.2032 -0.18796) (xy -0.20701 -0.19685) (xy -0.21209 -0.20701)
						(xy -0.2159 -0.21717) (xy -0.21844 -0.22733) (xy -0.22225 -0.23876) (xy -0.22352 -0.24892) (xy -0.22606 -0.25908)
						(xy -0.22733 -0.27051) (xy -0.22733 -0.28067) (xy -0.2286 -0.2921) (xy -0.22733 -0.30353) (xy -0.22733 -0.31369)
						(xy -0.22606 -0.32512) (xy -0.22352 -0.33528) (xy -0.22225 -0.34544) (xy -0.21844 -0.35687) (xy -0.2159 -0.36703)
						(xy -0.21209 -0.37719) (xy -0.20701 -0.38735) (xy -0.2032 -0.39624) (xy -0.19812 -0.4064) (xy -0.17272 -0.44196)
						(xy -0.1651 -0.44958) (xy -0.1651 -0.7366) (xy -0.16256 -0.76835) (xy -0.1524 -0.8001) (xy -0.13716 -0.82804)
						(xy -0.11684 -0.85344) (xy -0.09144 -0.87376) (xy -0.0635 -0.889) (xy -0.03175 -0.89916) (xy 0 -0.9017)
						(xy 0.03175 -0.89916) (xy 0.0635 -0.889) (xy 0.09144 -0.87376) (xy 0.11684 -0.85344) (xy 0.13716 -0.82804)
						(xy 0.1524 -0.8001) (xy 0.16256 -0.76835) (xy 0.1651 -0.7366) (xy 0.1651 -0.44958) (xy 0.17272 -0.44196)
						(xy 0.19812 -0.4064) (xy 0.2032 -0.39624) (xy 0.20701 -0.38735) (xy 0.21209 -0.37719) (xy 0.2159 -0.36703)
						(xy 0.21844 -0.35687) (xy 0.22225 -0.34544) (xy 0.22352 -0.33528) (xy 0.22606 -0.32512) (xy 0.22733 -0.31369)
						(xy 0.22733 -0.30353) (xy 0.2286 -0.2921) (xy 0.22733 -0.28067) (xy 0.22733 -0.27051) (xy 0.22606 -0.25908)
						(xy 0.22352 -0.24892) (xy 0.22225 -0.23876) (xy 0.21844 -0.22733) (xy 0.2159 -0.21717) (xy 0.21209 -0.20701)
						(xy 0.20701 -0.19685) (xy 0.2032 -0.18796) (xy 0.19812 -0.1778) (xy 0.17272 -0.14224) (xy 0.1651 -0.13462)
						(xy 0.1651 0.7366) (xy 0.16256 0.76835) (xy 0.1524 0.8001) (xy 0.13716 0.82804) (xy 0.11684 0.85344)
						(xy 0.09144 0.87376) (xy 0.0635 0.889) (xy 0.03175 0.89916)
					)
					(width 0)
					(fill yes)
				)
			)
		)
		(pad "190" smd custom
			(at 27.450034 -4.106672)
			(size 0.1143 0.1143)
			(layers "F.Cu" "F.Mask" "F.Paste")
			(net "GND")
			(options
				(clearance outline)
				(anchor circle)
			)
			(primitives
				(gr_poly
					(pts
						(xy 0 0.9017) (xy -0.03175 0.89916) (xy -0.0635 0.889) (xy -0.09144 0.87376) (xy -0.11684 0.85344)
						(xy -0.13716 0.82804) (xy -0.1524 0.8001) (xy -0.16256 0.76835) (xy -0.1651 0.7366) (xy -0.1651 0.44958)
						(xy -0.17272 0.44196) (xy -0.19812 0.4064) (xy -0.2032 0.39624) (xy -0.20701 0.38735) (xy -0.21209 0.37719)
						(xy -0.2159 0.36703) (xy -0.21844 0.35687) (xy -0.22225 0.34544) (xy -0.22352 0.33528) (xy -0.22606 0.32512)
						(xy -0.22733 0.31369) (xy -0.22733 0.30353) (xy -0.2286 0.2921) (xy -0.22733 0.28067) (xy -0.22733 0.27051)
						(xy -0.22606 0.25908) (xy -0.22352 0.24892) (xy -0.22225 0.23876) (xy -0.21844 0.22733) (xy -0.2159 0.21717)
						(xy -0.21209 0.20701) (xy -0.20701 0.19685) (xy -0.2032 0.18796) (xy -0.19812 0.1778) (xy -0.17272 0.14224)
						(xy -0.1651 0.13462) (xy -0.1651 -0.7366) (xy -0.16256 -0.76835) (xy -0.1524 -0.8001) (xy -0.13716 -0.82804)
						(xy -0.11684 -0.85344) (xy -0.09144 -0.87376) (xy -0.0635 -0.889) (xy -0.03175 -0.89916) (xy 0 -0.9017)
						(xy 0.03175 -0.89916) (xy 0.0635 -0.889) (xy 0.09144 -0.87376) (xy 0.11684 -0.85344) (xy 0.13716 -0.82804)
						(xy 0.1524 -0.8001) (xy 0.16256 -0.76835) (xy 0.1651 -0.7366) (xy 0.1651 0.13462) (xy 0.17272 0.14224)
						(xy 0.19812 0.1778) (xy 0.2032 0.18796) (xy 0.20701 0.19685) (xy 0.21209 0.20701) (xy 0.2159 0.21717)
						(xy 0.21844 0.22733) (xy 0.22225 0.23876) (xy 0.22352 0.24892) (xy 0.22606 0.25908) (xy 0.22733 0.27051)
						(xy 0.22733 0.28067) (xy 0.2286 0.2921) (xy 0.22733 0.30353) (xy 0.22733 0.31369) (xy 0.22606 0.32512)
						(xy 0.22352 0.33528) (xy 0.22225 0.34544) (xy 0.21844 0.35687) (xy 0.2159 0.36703) (xy 0.21209 0.37719)
						(xy 0.20701 0.38735) (xy 0.2032 0.39624) (xy 0.19812 0.4064) (xy 0.17272 0.44196) (xy 0.1651 0.44958)
						(xy 0.1651 0.7366) (xy 0.16256 0.76835) (xy 0.1524 0.8001) (xy 0.13716 0.82804) (xy 0.11684 0.85344)
						(xy 0.09144 0.87376) (xy 0.0635 0.889) (xy 0.03175 0.89916)
					)
					(width 0)
					(fill yes)
				)
			)
		)
		(pad "191" smd custom
			(at 27.750008 4.106672)
			(size 0.1143 0.1143)
			(layers "F.Cu" "F.Mask" "F.Paste")
			(net "M_B_DQ62")
			(options
				(clearance outline)
				(anchor circle)
			)
			(primitives
				(gr_poly
					(pts
						(xy 0 0.9017) (xy -0.03175 0.89916) (xy -0.0635 0.889) (xy -0.09144 0.87376) (xy -0.11684 0.85344)
						(xy -0.13716 0.82804) (xy -0.1524 0.8001) (xy -0.16256 0.76835) (xy -0.1651 0.7366) (xy -0.1651 0.11938)
						(xy -0.17272 0.11176) (xy -0.19812 0.0762) (xy -0.2032 0.06604) (xy -0.20701 0.05715) (xy -0.21209 0.04699)
						(xy -0.2159 0.03683) (xy -0.21844 0.02667) (xy -0.22225 0.01524) (xy -0.22352 0.00508) (xy -0.22606 -0.00508)
						(xy -0.22733 -0.01651) (xy -0.22733 -0.02667) (xy -0.2286 -0.0381) (xy -0.22733 -0.04953) (xy -0.22733 -0.05969)
						(xy -0.22606 -0.07112) (xy -0.22352 -0.08128) (xy -0.22225 -0.09144) (xy -0.21844 -0.10287) (xy -0.2159 -0.11303)
						(xy -0.21209 -0.12319) (xy -0.20701 -0.13335) (xy -0.2032 -0.14224) (xy -0.19812 -0.1524) (xy -0.17272 -0.18796)
						(xy -0.1651 -0.19558) (xy -0.1651 -0.7366) (xy -0.16256 -0.76835) (xy -0.1524 -0.8001) (xy -0.13716 -0.82804)
						(xy -0.11684 -0.85344) (xy -0.09144 -0.87376) (xy -0.0635 -0.889) (xy -0.03175 -0.89916) (xy 0 -0.9017)
						(xy 0.03175 -0.89916) (xy 0.0635 -0.889) (xy 0.09144 -0.87376) (xy 0.11684 -0.85344) (xy 0.13716 -0.82804)
						(xy 0.1524 -0.8001) (xy 0.16256 -0.76835) (xy 0.1651 -0.7366) (xy 0.1651 -0.19685) (xy 0.17272 -0.18923)
						(xy 0.17907 -0.18034) (xy 0.18669 -0.17145) (xy 0.19177 -0.16256) (xy 0.19812 -0.15367) (xy 0.20828 -0.13335)
						(xy 0.21971 -0.10287) (xy 0.22225 -0.09271) (xy 0.22479 -0.08128) (xy 0.22606 -0.07112) (xy 0.2286 -0.05969)
						(xy 0.2286 -0.01651) (xy 0.22606 -0.00508) (xy 0.22479 0.00508) (xy 0.22225 0.01651) (xy 0.21971 0.02667)
						(xy 0.20828 0.05715) (xy 0.19812 0.07747) (xy 0.19177 0.08636) (xy 0.18669 0.09525) (xy 0.17907 0.10414)
						(xy 0.17272 0.11303) (xy 0.1651 0.12065) (xy 0.1651 0.7366) (xy 0.16256 0.76835) (xy 0.1524 0.8001)
						(xy 0.13716 0.82804) (xy 0.11684 0.85344) (xy 0.09144 0.87376) (xy 0.0635 0.889) (xy 0.03175 0.89916)
					)
					(width 0)
					(fill yes)
				)
			)
		)
		(pad "192" smd custom
			(at 28.049982 -4.106672)
			(size 0.1143 0.1143)
			(layers "F.Cu" "F.Mask" "F.Paste")
			(net "M_B_DQ58")
			(options
				(clearance outline)
				(anchor circle)
			)
			(primitives
				(gr_poly
					(pts
						(xy 0 0.9017) (xy -0.03175 0.89916) (xy -0.0635 0.889) (xy -0.09144 0.87376) (xy -0.11684 0.85344)
						(xy -0.13716 0.82804) (xy -0.1524 0.8001) (xy -0.16256 0.76835) (xy -0.1651 0.7366) (xy -0.1651 0.19685)
						(xy -0.17272 0.18923) (xy -0.17907 0.18034) (xy -0.18669 0.17145) (xy -0.19177 0.16256) (xy -0.19812 0.15367)
						(xy -0.20828 0.13335) (xy -0.21971 0.10287) (xy -0.22225 0.09271) (xy -0.22479 0.08128) (xy -0.22606 0.07112)
						(xy -0.2286 0.05969) (xy -0.2286 0.01651) (xy -0.22606 0.00508) (xy -0.22479 -0.00508) (xy -0.22225 -0.01651)
						(xy -0.21971 -0.02667) (xy -0.20828 -0.05715) (xy -0.19812 -0.07747) (xy -0.19177 -0.08636) (xy -0.18669 -0.09525)
						(xy -0.17907 -0.10414) (xy -0.17272 -0.11303) (xy -0.1651 -0.12065) (xy -0.1651 -0.7366) (xy -0.16256 -0.76835)
						(xy -0.1524 -0.8001) (xy -0.13716 -0.82804) (xy -0.11684 -0.85344) (xy -0.09144 -0.87376) (xy -0.0635 -0.889)
						(xy -0.03175 -0.89916) (xy 0 -0.9017) (xy 0.03175 -0.89916) (xy 0.0635 -0.889) (xy 0.09144 -0.87376)
						(xy 0.11684 -0.85344) (xy 0.13716 -0.82804) (xy 0.1524 -0.8001) (xy 0.16256 -0.76835) (xy 0.1651 -0.7366)
						(xy 0.1651 -0.11938) (xy 0.17272 -0.11176) (xy 0.19812 -0.0762) (xy 0.2032 -0.06604) (xy 0.20701 -0.05715)
						(xy 0.21209 -0.04699) (xy 0.2159 -0.03683) (xy 0.21844 -0.02667) (xy 0.22225 -0.01524) (xy 0.22352 -0.00508)
						(xy 0.22606 0.00508) (xy 0.22733 0.01651) (xy 0.22733 0.02667) (xy 0.2286 0.0381) (xy 0.22733 0.04953)
						(xy 0.22733 0.05969) (xy 0.22606 0.07112) (xy 0.22352 0.08128) (xy 0.22225 0.09144) (xy 0.21844 0.10287)
						(xy 0.2159 0.11303) (xy 0.21209 0.12319) (xy 0.20701 0.13335) (xy 0.2032 0.14224) (xy 0.19812 0.1524)
						(xy 0.17272 0.18796) (xy 0.1651 0.19558) (xy 0.1651 0.7366) (xy 0.16256 0.76835) (xy 0.1524 0.8001)
						(xy 0.13716 0.82804) (xy 0.11684 0.85344) (xy 0.09144 0.87376) (xy 0.0635 0.889) (xy 0.03175 0.89916)
					)
					(width 0)
					(fill yes)
				)
			)
		)
		(pad "193" smd custom
			(at 28.349956 4.106672)
			(size 0.1143 0.1143)
			(layers "F.Cu" "F.Mask" "F.Paste")
			(net "M_B_DQ63")
			(options
				(clearance outline)
				(anchor circle)
			)
			(primitives
				(gr_poly
					(pts
						(xy 0 0.9017) (xy -0.03175 0.89916) (xy -0.0635 0.889) (xy -0.09144 0.87376) (xy -0.11684 0.85344)
						(xy -0.13716 0.82804) (xy -0.1524 0.8001) (xy -0.16256 0.76835) (xy -0.1651 0.7366) (xy -0.1651 -0.13462)
						(xy -0.17272 -0.14224) (xy -0.19812 -0.1778) (xy -0.2032 -0.18796) (xy -0.20701 -0.19685) (xy -0.21209 -0.20701)
						(xy -0.2159 -0.21717) (xy -0.21844 -0.22733) (xy -0.22225 -0.23876) (xy -0.22352 -0.24892) (xy -0.22606 -0.25908)
						(xy -0.22733 -0.27051) (xy -0.22733 -0.28067) (xy -0.2286 -0.2921) (xy -0.22733 -0.30353) (xy -0.22733 -0.31369)
						(xy -0.22606 -0.32512) (xy -0.22352 -0.33528) (xy -0.22225 -0.34544) (xy -0.21844 -0.35687) (xy -0.2159 -0.36703)
						(xy -0.21209 -0.37719) (xy -0.20701 -0.38735) (xy -0.2032 -0.39624) (xy -0.19812 -0.4064) (xy -0.17272 -0.44196)
						(xy -0.1651 -0.44958) (xy -0.1651 -0.7366) (xy -0.16256 -0.76835) (xy -0.1524 -0.8001) (xy -0.13716 -0.82804)
						(xy -0.11684 -0.85344) (xy -0.09144 -0.87376) (xy -0.0635 -0.889) (xy -0.03175 -0.89916) (xy 0 -0.9017)
						(xy 0.03175 -0.89916) (xy 0.0635 -0.889) (xy 0.09144 -0.87376) (xy 0.11684 -0.85344) (xy 0.13716 -0.82804)
						(xy 0.1524 -0.8001) (xy 0.16256 -0.76835) (xy 0.1651 -0.7366) (xy 0.1651 -0.44958) (xy 0.17272 -0.44196)
						(xy 0.19812 -0.4064) (xy 0.2032 -0.39624) (xy 0.20701 -0.38735) (xy 0.21209 -0.37719) (xy 0.2159 -0.36703)
						(xy 0.21844 -0.35687) (xy 0.22225 -0.34544) (xy 0.22352 -0.33528) (xy 0.22606 -0.32512) (xy 0.22733 -0.31369)
						(xy 0.22733 -0.30353) (xy 0.2286 -0.2921) (xy 0.22733 -0.28067) (xy 0.22733 -0.27051) (xy 0.22606 -0.25908)
						(xy 0.22352 -0.24892) (xy 0.22225 -0.23876) (xy 0.21844 -0.22733) (xy 0.2159 -0.21717) (xy 0.21209 -0.20701)
						(xy 0.20701 -0.19685) (xy 0.2032 -0.18796) (xy 0.19812 -0.1778) (xy 0.17272 -0.14224) (xy 0.1651 -0.13462)
						(xy 0.1651 0.7366) (xy 0.16256 0.76835) (xy 0.1524 0.8001) (xy 0.13716 0.82804) (xy 0.11684 0.85344)
						(xy 0.09144 0.87376) (xy 0.0635 0.889) (xy 0.03175 0.89916)
					)
					(width 0)
					(fill yes)
				)
			)
		)
		(pad "194" smd custom
			(at 28.64993 -4.106672)
			(size 0.1143 0.1143)
			(layers "F.Cu" "F.Mask" "F.Paste")
			(net "M_B_DQ59")
			(options
				(clearance outline)
				(anchor circle)
			)
			(primitives
				(gr_poly
					(pts
						(xy 0 0.9017) (xy -0.03175 0.89916) (xy -0.0635 0.889) (xy -0.09144 0.87376) (xy -0.11684 0.85344)
						(xy -0.13716 0.82804) (xy -0.1524 0.8001) (xy -0.16256 0.76835) (xy -0.1651 0.7366) (xy -0.1651 0.44958)
						(xy -0.17272 0.44196) (xy -0.19812 0.4064) (xy -0.2032 0.39624) (xy -0.20701 0.38735) (xy -0.21209 0.37719)
						(xy -0.2159 0.36703) (xy -0.21844 0.35687) (xy -0.22225 0.34544) (xy -0.22352 0.33528) (xy -0.22606 0.32512)
						(xy -0.22733 0.31369) (xy -0.22733 0.30353) (xy -0.2286 0.2921) (xy -0.22733 0.28067) (xy -0.22733 0.27051)
						(xy -0.22606 0.25908) (xy -0.22352 0.24892) (xy -0.22225 0.23876) (xy -0.21844 0.22733) (xy -0.2159 0.21717)
						(xy -0.21209 0.20701) (xy -0.20701 0.19685) (xy -0.2032 0.18796) (xy -0.19812 0.1778) (xy -0.17272 0.14224)
						(xy -0.1651 0.13462) (xy -0.1651 -0.7366) (xy -0.16256 -0.76835) (xy -0.1524 -0.8001) (xy -0.13716 -0.82804)
						(xy -0.11684 -0.85344) (xy -0.09144 -0.87376) (xy -0.0635 -0.889) (xy -0.03175 -0.89916) (xy 0 -0.9017)
						(xy 0.03175 -0.89916) (xy 0.0635 -0.889) (xy 0.09144 -0.87376) (xy 0.11684 -0.85344) (xy 0.13716 -0.82804)
						(xy 0.1524 -0.8001) (xy 0.16256 -0.76835) (xy 0.1651 -0.7366) (xy 0.1651 0.13462) (xy 0.17272 0.14224)
						(xy 0.19812 0.1778) (xy 0.2032 0.18796) (xy 0.20701 0.19685) (xy 0.21209 0.20701) (xy 0.2159 0.21717)
						(xy 0.21844 0.22733) (xy 0.22225 0.23876) (xy 0.22352 0.24892) (xy 0.22606 0.25908) (xy 0.22733 0.27051)
						(xy 0.22733 0.28067) (xy 0.2286 0.2921) (xy 0.22733 0.30353) (xy 0.22733 0.31369) (xy 0.22606 0.32512)
						(xy 0.22352 0.33528) (xy 0.22225 0.34544) (xy 0.21844 0.35687) (xy 0.2159 0.36703) (xy 0.21209 0.37719)
						(xy 0.20701 0.38735) (xy 0.2032 0.39624) (xy 0.19812 0.4064) (xy 0.17272 0.44196) (xy 0.1651 0.44958)
						(xy 0.1651 0.7366) (xy 0.16256 0.76835) (xy 0.1524 0.8001) (xy 0.13716 0.82804) (xy 0.11684 0.85344)
						(xy 0.09144 0.87376) (xy 0.0635 0.889) (xy 0.03175 0.89916)
					)
					(width 0)
					(fill yes)
				)
			)
		)
		(pad "195" smd custom
			(at 28.949904 4.106672)
			(size 0.1143 0.1143)
			(layers "F.Cu" "F.Mask" "F.Paste")
			(net "GND")
			(options
				(clearance outline)
				(anchor circle)
			)
			(primitives
				(gr_poly
					(pts
						(xy 0 0.9017) (xy -0.03175 0.89916) (xy -0.0635 0.889) (xy -0.09144 0.87376) (xy -0.11684 0.85344)
						(xy -0.13716 0.82804) (xy -0.1524 0.8001) (xy -0.16256 0.76835) (xy -0.1651 0.7366) (xy -0.1651 0.11938)
						(xy -0.17272 0.11176) (xy -0.19812 0.0762) (xy -0.2032 0.06604) (xy -0.20701 0.05715) (xy -0.21209 0.04699)
						(xy -0.2159 0.03683) (xy -0.21844 0.02667) (xy -0.22225 0.01524) (xy -0.22352 0.00508) (xy -0.22606 -0.00508)
						(xy -0.22733 -0.01651) (xy -0.22733 -0.02667) (xy -0.2286 -0.0381) (xy -0.22733 -0.04953) (xy -0.22733 -0.05969)
						(xy -0.22606 -0.07112) (xy -0.22352 -0.08128) (xy -0.22225 -0.09144) (xy -0.21844 -0.10287) (xy -0.2159 -0.11303)
						(xy -0.21209 -0.12319) (xy -0.20701 -0.13335) (xy -0.2032 -0.14224) (xy -0.19812 -0.1524) (xy -0.17272 -0.18796)
						(xy -0.1651 -0.19558) (xy -0.1651 -0.7366) (xy -0.16256 -0.76835) (xy -0.1524 -0.8001) (xy -0.13716 -0.82804)
						(xy -0.11684 -0.85344) (xy -0.09144 -0.87376) (xy -0.0635 -0.889) (xy -0.03175 -0.89916) (xy 0 -0.9017)
						(xy 0.03175 -0.89916) (xy 0.0635 -0.889) (xy 0.09144 -0.87376) (xy 0.11684 -0.85344) (xy 0.13716 -0.82804)
						(xy 0.1524 -0.8001) (xy 0.16256 -0.76835) (xy 0.1651 -0.7366) (xy 0.1651 -0.19685) (xy 0.17272 -0.18923)
						(xy 0.17907 -0.18034) (xy 0.18669 -0.17145) (xy 0.19177 -0.16256) (xy 0.19812 -0.15367) (xy 0.20828 -0.13335)
						(xy 0.21971 -0.10287) (xy 0.22225 -0.09271) (xy 0.22479 -0.08128) (xy 0.22606 -0.07112) (xy 0.2286 -0.05969)
						(xy 0.2286 -0.01651) (xy 0.22606 -0.00508) (xy 0.22479 0.00508) (xy 0.22225 0.01651) (xy 0.21971 0.02667)
						(xy 0.20828 0.05715) (xy 0.19812 0.07747) (xy 0.19177 0.08636) (xy 0.18669 0.09525) (xy 0.17907 0.10414)
						(xy 0.17272 0.11303) (xy 0.1651 0.12065) (xy 0.1651 0.7366) (xy 0.16256 0.76835) (xy 0.1524 0.8001)
						(xy 0.13716 0.82804) (xy 0.11684 0.85344) (xy 0.09144 0.87376) (xy 0.0635 0.889) (xy 0.03175 0.89916)
					)
					(width 0)
					(fill yes)
				)
			)
		)
	)
)
